FILE_TYPE = MULTI_PHYS_TABLE;

PART 'MPQ8633BGLEC838Z'

{========================================================================================}
:VALUE                | PART_TYPE | MATERIAL | PART_NUMBER    = STANDARD    | LIFECYCLE     | PART_NUMBER   | JEDEC_TYPE  | DESCRIPTION                            | MANUFTR | MANUF_PN             | RD_CMPLS_LVL | CMPLS_LVL | FROM_PJ    | CLASS | DIP_SMD | DATA                         | EE_CHECK_LIST | FP_ECN | PSL | CREATOR | STATUS | MSD  | ESD_CDM | ESD_HBM | ESD_MM | PIN_LENGTH_SHORT_PIN | PIN_LENGTH_LONG_PIN | CREATEDAY  ;
{========================================================================================}
 'MPQ8633BGLE-C838-Z' | 'SMLF'    | 'IC'     | 'AL008633005'(!) = ''               | ''               | 'AL008633005' |'QFN14_4X3'| 'IC CTRL(21P) MPQ8633BGLE-C838-Z(QFN)' | 'MPS'   | 'MPQ8633BGLE-C838-Z' | 'EP(V1)'     | ''        | 'F09-ABER' | 'IC'  | ''      | 'MPS_MPQ8633BGLE-C838-Z.pdf' | ''            | ''     | ''  | ''      | ''     | 'NA' | 'NA'    | 'NA'    | 'NA'   | '0 MILS'             | '0 MILS'            | '20171113'
 'MPQ8633BGLE-C838-Z' | 'SMLF'    | 'EMPTY'  | 'AL008633005'(!) = ''               | ''               | 'AL008633005' |'QFN14_4X3'| 'IC CTRL(21P) MPQ8633BGLE-C838-Z(QFN)' | 'MPS'   | 'MPQ8633BGLE-C838-Z' | 'EP(V1)'     | ''        | 'F09-ABER' | 'IC'  | ''      | 'MPS_MPQ8633BGLE-C838-Z.pdf' | ''            | ''     | ''  | ''      | ''     | 'NA' | 'NA'    | 'NA'    | 'NA'   | '0 MILS'             | '0 MILS'            | '20171113'

END_PART

END.

